(kicad_pcb
	(version 20260206)
	(generator "pcbnew")
	(generator_version "10.0")
	(general
		(thickness 1.6)
		(legacy_teardrops no)
	)
	(paper "A4")
	(title_block
		(title "Wiwynn_Tioga_Pass_MB.brd")
		(comment 1 "Tioga Pass / footprints 422-428 of 4770")
	)
	(layers
		(0 "F.Cu" signal "TOP")
		(4 "In1.Cu" signal "L2GND")
		(6 "In2.Cu" signal "L3")
		(8 "In3.Cu" signal "L4GND")
		(10 "In4.Cu" signal "L5")
		(12 "In5.Cu" signal "L6GND")
		(14 "In6.Cu" signal "L7VCC")
		(16 "In7.Cu" signal "L8VCC")
		(18 "In8.Cu" signal "L9GND")
		(20 "In9.Cu" signal "L10")
		(22 "In10.Cu" signal "L11GND")
		(24 "In11.Cu" signal "L12")
		(26 "In12.Cu" signal "L13GND")
		(2 "B.Cu" signal "BOTTOM")
		(9 "F.Adhes" user "F.Adhesive")
		(11 "B.Adhes" user "B.Adhesive")
		(13 "F.Paste" user "Package Geometry/Pastemask Top")
		(15 "B.Paste" user "Package Geometry/Pastemask Bottom")
		(5 "F.SilkS" user "Ref Des/Silkscreen Top")
		(7 "B.SilkS" user "Ref Des/Silkscreen Bottom")
		(1 "F.Mask" user "Board Geometry/Soldermask Top")
		(3 "B.Mask" user "Board Geometry/Soldermask Bottom")
		(17 "Dwgs.User" user "User.Drawings")
		(19 "Cmts.User" user "User.Comments")
		(21 "Eco1.User" user "User.Eco1")
		(23 "Eco2.User" user "User.Eco2")
		(25 "Edge.Cuts" user "Board Geometry/Outline")
		(27 "Margin" user)
		(31 "F.CrtYd" user "Package Geometry/Place Bound Top")
		(29 "B.CrtYd" user "Package Geometry/Place Bound Bottom")
		(35 "F.Fab" user "Ref Des/Assembly Top")
		(33 "B.Fab" user "Ref Des/Assembly Bottom")
	)
	(footprint ""
		(layer "F.Cu")
		(at 411.1625 -105.537 -90)
		(property "Reference" "R8C18"
			(at 0 0 270)
			(layer "F.SilkS")
			(hide yes)
			(effects
				(font
					(size 1.27 1.27)
				)
			)
		)
		(property "Value" ""
			(at 0 0 270)
			(layer "F.Fab")
			(effects
				(font
					(size 1.27 1.27)
				)
			)
		)
		(duplicate_pad_numbers_are_jumpers no)
		(fp_poly
			(pts
				(xy -0.2794 -0.1016) (xy 0.2794 -0.1016) (xy 0.2794 0.9906) (xy -0.2794 0.9906)
			)
			(stroke
				(width 0)
				(type default)
			)
			(fill no)
			(layer "F.CrtYd")
		)
		(fp_line
			(start -0.2794 0.9906)
			(end 0.2794 0.9906)
			(stroke
				(width 0.1)
				(type default)
			)
			(layer "F.Fab")
		)
		(fp_line
			(start 0.2794 0.9906)
			(end 0.2794 -0.1016)
			(stroke
				(width 0.1)
				(type default)
			)
			(layer "F.Fab")
		)
		(fp_line
			(start -0.2794 -0.1016)
			(end -0.2794 0.9906)
			(stroke
				(width 0.1)
				(type default)
			)
			(layer "F.Fab")
		)
		(fp_line
			(start 0.2794 -0.1016)
			(end -0.2794 -0.1016)
			(stroke
				(width 0.1)
				(type default)
			)
			(layer "F.Fab")
		)
		(pad "1" smd rect
			(at 0 0 270)
			(size 0.508 0.508)
			(layers "F.Cu" "F.Mask" "F.Paste")
			(net "P3V3_STBY")
		)
		(pad "2" smd rect
			(at 0 0.889 270)
			(size 0.508 0.508)
			(layers "F.Cu" "F.Mask" "F.Paste")
			(net "PU_PCH_TLS_ENABLE_STRAP")
		)
		(zone
			(layer "F.Cu")
			(hatch none 0.5)
			(connect_pads
				(clearance 0)
			)
			(min_thickness 0.25)
			(keepout
				(tracks not_allowed)
				(vias allowed)
				(pads allowed)
				(copperpour not_allowed)
				(footprints allowed)
			)
			(placement
				(enabled no)
				(sheetname "")
			)
			(fill
				(thermal_gap 0.5)
				(thermal_bridge_width 0.5)
				(island_removal_mode 0)
			)
			(polygon
				(pts
					(xy 410.5275 -105.791) (xy 410.5275 -105.283) (xy 410.9085 -105.283) (xy 410.9085 -105.791)
				)
			)
		)
		(zone
			(layer "F.Cu")
			(hatch none 0.5)
			(connect_pads
				(clearance 0)
			)
			(min_thickness 0.25)
			(keepout
				(tracks allowed)
				(vias not_allowed)
				(pads allowed)
				(copperpour not_allowed)
				(footprints allowed)
			)
			(placement
				(enabled no)
				(sheetname "")
			)
			(fill
				(thermal_gap 0.5)
				(thermal_bridge_width 0.5)
				(island_removal_mode 0)
			)
			(polygon
				(pts
					(xy 410.9085 -105.791) (xy 410.9085 -105.283) (xy 410.5275 -105.283) (xy 410.5275 -105.791)
				)
			)
		)
	)
	(footprint ""
		(layer "F.Cu")
		(at 162.306 -65.7606 90)
		(property "Reference" "SH3D1"
			(at 0 0 90)
			(layer "F.SilkS")
			(hide yes)
			(effects
				(font
					(size 1.27 1.27)
				)
			)
		)
		(property "Value" ""
			(at 0 0 90)
			(layer "F.Fab")
			(effects
				(font
					(size 1.27 1.27)
				)
			)
		)
		(duplicate_pad_numbers_are_jumpers no)
		(fp_poly
			(pts
				(xy -0.1651 -0.0508) (xy -0.1651 0.5842) (xy 0.1651 0.5842) (xy 0.1651 -0.0508)
			)
			(stroke
				(width 0)
				(type default)
			)
			(fill no)
			(layer "F.CrtYd")
		)
		(fp_line
			(start 0.1651 -0.0508)
			(end 0.1651 0.5842)
			(stroke
				(width 0.1)
				(type default)
			)
			(layer "F.Fab")
		)
		(fp_line
			(start -0.1651 -0.0508)
			(end 0.1651 -0.0508)
			(stroke
				(width 0.1)
				(type default)
			)
			(layer "F.Fab")
		)
		(fp_line
			(start 0.1651 0.5842)
			(end -0.1651 0.5842)
			(stroke
				(width 0.1)
				(type default)
			)
			(layer "F.Fab")
		)
		(fp_line
			(start -0.1651 0.5842)
			(end -0.1651 -0.0508)
			(stroke
				(width 0.1)
				(type default)
			)
			(layer "F.Fab")
		)
		(pad "1" smd custom
			(at 0 0 270)
			(size 0.0762 0.0762)
			(layers "F.Cu" "F.Mask" "F.Paste")
			(net "VSENSE_PVCCIO_CPU1_SKT_VRTN")
			(options
				(clearance outline)
				(anchor circle)
			)
			(primitives
				(gr_poly
					(pts
						(arc
							(start -0.1524 -0.10795)
							(mid -0.098518 -0.130268)
							(end -0.0762 -0.18415)
						)
						(xy -0.0762 -0.22225) (xy 0.0762 -0.22225)
						(arc
							(start 0.0762 -0.18415)
							(mid 0.098518 -0.130268)
							(end 0.1524 -0.10795)
						)
						(xy 0.1524 0.22225) (xy -0.1524 0.22225)
					)
					(width 0)
					(fill yes)
				)
			)
		)
		(pad "2" smd custom
			(at 0 0.5334 90)
			(size 0.0762 0.0762)
			(layers "F.Cu" "F.Mask" "F.Paste")
			(net "VSENSE_PVCCIO_CPU1_AVSN")
			(options
				(clearance outline)
				(anchor circle)
			)
			(primitives
				(gr_poly
					(pts
						(arc
							(start -0.1524 -0.10795)
							(mid -0.098518 -0.130268)
							(end -0.0762 -0.18415)
						)
						(xy -0.0762 -0.22225) (xy 0.0762 -0.22225)
						(arc
							(start 0.0762 -0.18415)
							(mid 0.098518 -0.130268)
							(end 0.1524 -0.10795)
						)
						(xy 0.1524 0.22225) (xy -0.1524 0.22225)
					)
					(width 0)
					(fill yes)
				)
			)
		)
	)
	(footprint ""
		(layer "F.Cu")
		(at 389.382 -66.3194)
		(property "Reference" "R7E17"
			(at 0 0 0)
			(layer "F.SilkS")
			(hide yes)
			(effects
				(font
					(size 1.27 1.27)
				)
			)
		)
		(property "Value" ""
			(at 0 0 0)
			(layer "F.Fab")
			(effects
				(font
					(size 1.27 1.27)
				)
			)
		)
		(duplicate_pad_numbers_are_jumpers no)
		(fp_poly
			(pts
				(xy -0.2794 -0.1016) (xy 0.2794 -0.1016) (xy 0.2794 0.9906) (xy -0.2794 0.9906)
			)
			(stroke
				(width 0)
				(type default)
			)
			(fill no)
			(layer "F.CrtYd")
		)
		(fp_line
			(start -0.2794 -0.1016)
			(end -0.2794 0.9906)
			(stroke
				(width 0.1)
				(type default)
			)
			(layer "F.Fab")
		)
		(fp_line
			(start -0.2794 0.9906)
			(end 0.2794 0.9906)
			(stroke
				(width 0.1)
				(type default)
			)
			(layer "F.Fab")
		)
		(fp_line
			(start 0.2794 -0.1016)
			(end -0.2794 -0.1016)
			(stroke
				(width 0.1)
				(type default)
			)
			(layer "F.Fab")
		)
		(fp_line
			(start 0.2794 0.9906)
			(end 0.2794 -0.1016)
			(stroke
				(width 0.1)
				(type default)
			)
			(layer "F.Fab")
		)
		(pad "1" smd rect
			(at 0 0)
			(size 0.508 0.508)
			(layers "F.Cu" "F.Mask" "F.Paste")
			(net "VR_FET_SW_P5V_STBY_PVIN")
		)
		(pad "2" smd rect
			(at 0 0.889)
			(size 0.508 0.508)
			(layers "F.Cu" "F.Mask" "F.Paste")
			(net "VR_P5V_STBY_VIN")
		)
		(zone
			(layer "F.Cu")
			(hatch none 0.5)
			(connect_pads
				(clearance 0)
			)
			(min_thickness 0.25)
			(keepout
				(tracks allowed)
				(vias not_allowed)
				(pads allowed)
				(copperpour not_allowed)
				(footprints allowed)
			)
			(placement
				(enabled no)
				(sheetname "")
			)
			(fill
				(thermal_gap 0.5)
				(thermal_bridge_width 0.5)
				(island_removal_mode 0)
			)
			(polygon
				(pts
					(xy 389.128 -66.0654) (xy 389.636 -66.0654) (xy 389.636 -65.6844) (xy 389.128 -65.6844)
				)
			)
		)
		(zone
			(layer "F.Cu")
			(hatch none 0.5)
			(connect_pads
				(clearance 0)
			)
			(min_thickness 0.25)
			(keepout
				(tracks not_allowed)
				(vias allowed)
				(pads allowed)
				(copperpour not_allowed)
				(footprints allowed)
			)
			(placement
				(enabled no)
				(sheetname "")
			)
			(fill
				(thermal_gap 0.5)
				(thermal_bridge_width 0.5)
				(island_removal_mode 0)
			)
			(polygon
				(pts
					(xy 389.128 -65.6844) (xy 389.636 -65.6844) (xy 389.636 -66.0654) (xy 389.128 -66.0654)
				)
			)
		)
	)
	(footprint ""
		(layer "F.Cu")
		(at 338.836 -13.1826 -90)
		(property "Reference" "C7G4"
			(at 0 0 270)
			(layer "F.SilkS")
			(hide yes)
			(effects
				(font
					(size 1.27 1.27)
				)
			)
		)
		(property "Value" ""
			(at 0 0 270)
			(layer "F.Fab")
			(effects
				(font
					(size 1.27 1.27)
				)
			)
		)
		(duplicate_pad_numbers_are_jumpers no)
		(fp_rect
			(start -0.3048 0.9906)
			(end 0.3048 -0.1016)
			(stroke
				(width 0)
				(type default)
			)
			(fill no)
			(layer "F.CrtYd")
		)
		(fp_line
			(start -0.3048 0.9906)
			(end 0.3048 0.9906)
			(stroke
				(width 0.1)
				(type default)
			)
			(layer "F.Fab")
		)
		(fp_line
			(start 0.3048 0.9906)
			(end 0.3048 -0.1016)
			(stroke
				(width 0.1)
				(type default)
			)
			(layer "F.Fab")
		)
		(fp_line
			(start -0.3048 -0.1016)
			(end -0.3048 0.9906)
			(stroke
				(width 0.1)
				(type default)
			)
			(layer "F.Fab")
		)
		(fp_line
			(start 0.3048 -0.1016)
			(end -0.3048 -0.1016)
			(stroke
				(width 0.1)
				(type default)
			)
			(layer "F.Fab")
		)
		(pad "1" smd rect
			(at 0 0 270)
			(size 0.508 0.508)
			(layers "F.Cu" "F.Mask" "F.Paste")
			(net "VR_PVDDQ_ABC_AVSP")
		)
		(pad "2" smd rect
			(at 0 0.889 270)
			(size 0.508 0.508)
			(layers "F.Cu" "F.Mask" "F.Paste")
			(net "VSENSE_PVDDQ_ABC_N")
		)
		(zone
			(layer "F.Cu")
			(hatch none 0.5)
			(connect_pads
				(clearance 0)
			)
			(min_thickness 0.25)
			(keepout
				(tracks allowed)
				(vias not_allowed)
				(pads allowed)
				(copperpour not_allowed)
				(footprints allowed)
			)
			(placement
				(enabled no)
				(sheetname "")
			)
			(fill
				(thermal_gap 0.5)
				(thermal_bridge_width 0.5)
				(island_removal_mode 0)
			)
			(polygon
				(pts
					(xy 338.201 -13.4366) (xy 338.201 -12.9286) (xy 338.582 -12.9286) (xy 338.582 -13.4366)
				)
			)
		)
	)
	(footprint ""
		(layer "F.Cu")
		(at 491.0455 -40.0304 90)
		(property "Reference" "R9F1"
			(at 0 0 90)
			(layer "F.SilkS")
			(hide yes)
			(effects
				(font
					(size 1.27 1.27)
				)
			)
		)
		(property "Value" ""
			(at 0 0 90)
			(layer "F.Fab")
			(effects
				(font
					(size 1.27 1.27)
				)
			)
		)
		(duplicate_pad_numbers_are_jumpers no)
		(fp_poly
			(pts
				(xy -0.2794 -0.1016) (xy 0.2794 -0.1016) (xy 0.2794 0.9906) (xy -0.2794 0.9906)
			)
			(stroke
				(width 0)
				(type default)
			)
			(fill no)
			(layer "F.CrtYd")
		)
		(fp_line
			(start 0.2794 -0.1016)
			(end -0.2794 -0.1016)
			(stroke
				(width 0.1)
				(type default)
			)
			(layer "F.Fab")
		)
		(fp_line
			(start -0.2794 -0.1016)
			(end -0.2794 0.9906)
			(stroke
				(width 0.1)
				(type default)
			)
			(layer "F.Fab")
		)
		(fp_line
			(start 0.2794 0.9906)
			(end 0.2794 -0.1016)
			(stroke
				(width 0.1)
				(type default)
			)
			(layer "F.Fab")
		)
		(fp_line
			(start -0.2794 0.9906)
			(end 0.2794 0.9906)
			(stroke
				(width 0.1)
				(type default)
			)
			(layer "F.Fab")
		)
		(pad "1" smd rect
			(at 0 0 90)
			(size 0.508 0.508)
			(layers "F.Cu" "F.Mask" "F.Paste")
			(net "RMII_BMC_PCH_SPRNGVLLE_CRSDV_R")
		)
		(pad "2" smd rect
			(at 0 0.889 90)
			(size 0.508 0.508)
			(layers "F.Cu" "F.Mask" "F.Paste")
			(net "RMII_BMC_PCH_SPRNGVLLE_CRSDV")
		)
		(zone
			(layer "F.Cu")
			(hatch none 0.5)
			(connect_pads
				(clearance 0)
			)
			(min_thickness 0.25)
			(keepout
				(tracks allowed)
				(vias not_allowed)
				(pads allowed)
				(copperpour not_allowed)
				(footprints allowed)
			)
			(placement
				(enabled no)
				(sheetname "")
			)
			(fill
				(thermal_gap 0.5)
				(thermal_bridge_width 0.5)
				(island_removal_mode 0)
			)
			(polygon
				(pts
					(xy 491.2995 -39.7764) (xy 491.2995 -40.2844) (xy 491.6805 -40.2844) (xy 491.6805 -39.7764)
				)
			)
		)
		(zone
			(layer "F.Cu")
			(hatch none 0.5)
			(connect_pads
				(clearance 0)
			)
			(min_thickness 0.25)
			(keepout
				(tracks not_allowed)
				(vias allowed)
				(pads allowed)
				(copperpour not_allowed)
				(footprints allowed)
			)
			(placement
				(enabled no)
				(sheetname "")
			)
			(fill
				(thermal_gap 0.5)
				(thermal_bridge_width 0.5)
				(island_removal_mode 0)
			)
			(polygon
				(pts
					(xy 491.6805 -39.7764) (xy 491.6805 -40.2844) (xy 491.2995 -40.2844) (xy 491.2995 -39.7764)
				)
			)
		)
	)
	(footprint ""
		(layer "F.Cu")
		(at 175.387 -81.407 90)
		(property "Reference" "R4D17"
			(at 0 0 90)
			(layer "F.SilkS")
			(hide yes)
			(effects
				(font
					(size 1.27 1.27)
				)
			)
		)
		(property "Value" ""
			(at 0 0 90)
			(layer "F.Fab")
			(effects
				(font
					(size 1.27 1.27)
				)
			)
		)
		(duplicate_pad_numbers_are_jumpers no)
		(fp_poly
			(pts
				(xy -0.2794 -0.1016) (xy 0.2794 -0.1016) (xy 0.2794 0.9906) (xy -0.2794 0.9906)
			)
			(stroke
				(width 0)
				(type default)
			)
			(fill no)
			(layer "F.CrtYd")
		)
		(fp_line
			(start 0.2794 -0.1016)
			(end -0.2794 -0.1016)
			(stroke
				(width 0.1)
				(type default)
			)
			(layer "F.Fab")
		)
		(fp_line
			(start -0.2794 -0.1016)
			(end -0.2794 0.9906)
			(stroke
				(width 0.1)
				(type default)
			)
			(layer "F.Fab")
		)
		(fp_line
			(start 0.2794 0.9906)
			(end 0.2794 -0.1016)
			(stroke
				(width 0.1)
				(type default)
			)
			(layer "F.Fab")
		)
		(fp_line
			(start -0.2794 0.9906)
			(end 0.2794 0.9906)
			(stroke
				(width 0.1)
				(type default)
			)
			(layer "F.Fab")
		)
		(pad "1" smd rect
			(at 0 0 90)
			(size 0.508 0.508)
			(layers "F.Cu" "F.Mask" "F.Paste")
			(net "CLK_100M_CPU0_BCLK2_R_DP")
		)
		(pad "2" smd rect
			(at 0 0.889 90)
			(size 0.508 0.508)
			(layers "F.Cu" "F.Mask" "F.Paste")
			(net "CLK_100M_CPU0_BCLK2_DP")
		)
		(zone
			(layer "F.Cu")
			(hatch none 0.5)
			(connect_pads
				(clearance 0)
			)
			(min_thickness 0.25)
			(keepout
				(tracks allowed)
				(vias not_allowed)
				(pads allowed)
				(copperpour not_allowed)
				(footprints allowed)
			)
			(placement
				(enabled no)
				(sheetname "")
			)
			(fill
				(thermal_gap 0.5)
				(thermal_bridge_width 0.5)
				(island_removal_mode 0)
			)
			(polygon
				(pts
					(xy 175.641 -81.153) (xy 175.641 -81.661) (xy 176.022 -81.661) (xy 176.022 -81.153)
				)
			)
		)
		(zone
			(layer "F.Cu")
			(hatch none 0.5)
			(connect_pads
				(clearance 0)
			)
			(min_thickness 0.25)
			(keepout
				(tracks not_allowed)
				(vias allowed)
				(pads allowed)
				(copperpour not_allowed)
				(footprints allowed)
			)
			(placement
				(enabled no)
				(sheetname "")
			)
			(fill
				(thermal_gap 0.5)
				(thermal_bridge_width 0.5)
				(island_removal_mode 0)
			)
			(polygon
				(pts
					(xy 176.022 -81.153) (xy 176.022 -81.661) (xy 175.641 -81.661) (xy 175.641 -81.153)
				)
			)
		)
	)
	(footprint ""
		(layer "F.Cu")
		(at 387.604 -88.2015)
		(property "Reference" "R7C20"
			(at 0 0 0)
			(layer "F.SilkS")
			(hide yes)
			(effects
				(font
					(size 1.27 1.27)
				)
			)
		)
		(property "Value" ""
			(at 0 0 0)
			(layer "F.Fab")
			(effects
				(font
					(size 1.27 1.27)
				)
			)
		)
		(duplicate_pad_numbers_are_jumpers no)
		(fp_poly
			(pts
				(xy -0.2794 -0.1016) (xy 0.2794 -0.1016) (xy 0.2794 0.9906) (xy -0.2794 0.9906)
			)
			(stroke
				(width 0)
				(type default)
			)
			(fill no)
			(layer "F.CrtYd")
		)
		(fp_line
			(start -0.2794 -0.1016)
			(end -0.2794 0.9906)
			(stroke
				(width 0.1)
				(type default)
			)
			(layer "F.Fab")
		)
		(fp_line
			(start -0.2794 0.9906)
			(end 0.2794 0.9906)
			(stroke
				(width 0.1)
				(type default)
			)
			(layer "F.Fab")
		)
		(fp_line
			(start 0.2794 -0.1016)
			(end -0.2794 -0.1016)
			(stroke
				(width 0.1)
				(type default)
			)
			(layer "F.Fab")
		)
		(fp_line
			(start 0.2794 0.9906)
			(end 0.2794 -0.1016)
			(stroke
				(width 0.1)
				(type default)
			)
			(layer "F.Fab")
		)
		(pad "1" smd rect
			(at 0 0)
			(size 0.508 0.508)
			(layers "F.Cu" "F.Mask" "F.Paste")
			(net "CLK_50M_CKMNG_PCH_10GBE")
		)
		(pad "2" smd rect
			(at 0 0.889)
			(size 0.508 0.508)
			(layers "F.Cu" "F.Mask" "F.Paste")
			(net "GND")
		)
		(zone
			(layer "F.Cu")
			(hatch none 0.5)
			(connect_pads
				(clearance 0)
			)
			(min_thickness 0.25)
			(keepout
				(tracks allowed)
				(vias not_allowed)
				(pads allowed)
				(copperpour not_allowed)
				(footprints allowed)
			)
			(placement
				(enabled no)
				(sheetname "")
			)
			(fill
				(thermal_gap 0.5)
				(thermal_bridge_width 0.5)
				(island_removal_mode 0)
			)
			(polygon
				(pts
					(xy 387.35 -87.9475) (xy 387.858 -87.9475) (xy 387.858 -87.5665) (xy 387.35 -87.5665)
				)
			)
		)
		(zone
			(layer "F.Cu")
			(hatch none 0.5)
			(connect_pads
				(clearance 0)
			)
			(min_thickness 0.25)
			(keepout
				(tracks not_allowed)
				(vias allowed)
				(pads allowed)
				(copperpour not_allowed)
				(footprints allowed)
			)
			(placement
				(enabled no)
				(sheetname "")
			)
			(fill
				(thermal_gap 0.5)
				(thermal_bridge_width 0.5)
				(island_removal_mode 0)
			)
			(polygon
				(pts
					(xy 387.35 -87.5665) (xy 387.858 -87.5665) (xy 387.858 -87.9475) (xy 387.35 -87.9475)
				)
			)
		)
	)
)
